FILE_TYPE = CONNECTIVITY;
{Allegro Design Entry HDL 17.2-2016 S081 (4005846) 1/11/2022}
"PAGE_NUMBER" = 184;
0"NC";
1"P3V3_STBY\g";
2"GND\g";
3"P3V3_STBY\g";
4"GND\g";
5"GND\g";
6"GND\g";
7"GND\g";
8"GND\g";
9"GND\g";
10"PWRGD_PVDD18_S5_P0";
11"FM_PWRGD_PVDD18_S5_P0";
12"VSENSE_PVDD18_S5_P0_DP";
13"VSENSE_PVDD18_S5_P0_DN";
14"GND\g";
15"PVDD18_S5_P0\g";
16"PVDD18_S5_P0_FB_RC";
17"SW_PVDD18_S5_P0_SW";
18"PVDD18_S5_P0_RGND";
19"PVDD18_S5_P0_REF";
20"GND\g";
21"PVDD18_S5_P0_CS";
22"PVDD18_S5_P0_EN";
23"P12V_STBY\g";
24"SW_PVDD18_S5_P0_BST";
25"PVDD18_S5_P0_FB";
26"SW_P12V_STBY_PVDD18_S5_P0_FLT";
27"GND\g";
28"PVDD18_S5_P0_MODE";
29"PVDD18_S5_P0_VCC";
%"Q_RES"
"2","(-7575,3050)","0","pure_quanta","I10";
;
LOCATION"PR477"
$SEC"1"
CDS_SEC"1"
WATTAGE"1/16W"
MATERIAL"CHIP"
TOLERANCE"5%"
VALUE"0"
PART_NUMBER"CS00002JB38"
PACK_TYPE"0402LF"
CDS_LIB"pure_quanta";
"A"
$PN"1"1;
"B"
$PN"2"29;
%"UNIVERSAL_POWER"
"1","(-7575,3250)","0","mstr_symbols","I11";
;
HDL_POWER"P3V3_STBY"
CDS_LIB"mstr_symbols";
"A"1;
%"Q_CAP"
"1","(-7575,4200)","0","pure_quanta","I12";
;
LOCATION"PC254"
$SEC"1"
CDS_SEC"1"
MATERIAL"X6S"
TOLERANCE"10%"
VALUE"10UF"
PART_NUMBER"CH6104KEA00"
VOLTAGE"25V"
PACK_TYPE"C0805"
CDS_LIB"pure_quanta";
"B"
$PN"2"27;
"A"
$PN"1"26;
%"Q_CAP"
"1","(-7125,4200)","0","pure_quanta","I13";
;
LOCATION"PC81"
$SEC"1"
CDS_SEC"1"
PART_NUMBER"CH6104KEA00"
VALUE"10UF"
MATERIAL"X6S"
TOLERANCE"10%"
VOLTAGE"25V"
PACK_TYPE"C0805"
CDS_LIB"pure_quanta";
"B"
$PN"2"27;
"A"
$PN"1"26;
%"Q_RES"
"2","(-6700,2625)","0","pure_quanta","I14";
;
LOCATION"PR448"
SEC"1"
WATTAGE"1/16W"
MATERIAL"CHIP"
TOLERANCE"1%"
VALUE"8.66K"
PART_NUMBER"CS28662FB14"
PACK_TYPE"0402LF"
CDS_LIB"pure_quanta"
SEC_TYPE"0402LF";
"A"
$PN"1"21;
"B"
$PN"2"9;
%"MPQ8633BGLEC838Z"
"1","(-5750,3475)","0","pure_quanta","I15";
;
LOCATION"PU57"
$SEC"1"
CDS_SEC"1"
PART_TYPE"SMLF"
MATERIAL"IC"
VALUE"MPQ8633BGLE-C838-Z"
PART_NUMBER"AL008633005"
CDS_LIB"pure_quanta"
NEEDS_NO_SIZE"TRUE"
CDS_LMAN_SYM_OUTLINE"-250,725,250,-725";
"VIN2"
$PN"21"26;
"CS"
$PN"3"21;
"MODE"
$PN"4"28;
"TRK_REF"
$PN"5"19;
"SW"
$PN"20"17;
"RGND"
$PN"6"18;
"VCC"
$PN"19"29;
"AGND"
$PN"2"20;
"FB"
$PN"7"25;
"BST"
$PN"1"24;
"EN"
$PN"8"22;
"PGND"
$PN"11_18"20;
"PGOOD"
$PN"9"10;
"VIN1"
$PN"10"26;
%"Q_CAP"
"1","(-6725,4200)","0","pure_quanta","I16";
;
LOCATION"PC237"
$SEC"1"
CDS_SEC"1"
VOLTAGE"25V"
MATERIAL"X7R"
TOLERANCE"10%"
VALUE"0.1UF"
PART_NUMBER"CH4104K1B00"
PACK_TYPE"0402"
SIGNAL_MODEL"DEFAULT_CAPACITOR_100000PF_2_1"
CDS_LIB"pure_quanta"
ROOM"VR_CORE1_POWER_STAGE_1";
"B"
$PN"2"27;
"A"
$PN"1"26;
%"UNIVERSAL_GND"
"1","(-5125,2525)","0","pure_quanta_power","I19";
;
CDS_LIB"pure_quanta_power"
HDL_POWER"GND";
"A"20;
%"Q_INDUCTOR"
"1","(-8875,4450)","0","pure_quanta","I2";
;
LOCATION"PL77"
$SEC"1"
CDS_SEC"1"
MATERIAL"IND"
VALUE"BLM18SN220TN1D/8000MA"
PART_NUMBER"CX220TN1001"
PACK_TYPE"SMLF"
CDS_LIB"pure_quanta"
NEEDS_NO_SIZE"TRUE";
"1"
$PN"1"23;
"2"
$PN"2"26;
%"UNIVERSAL_GND"
"1","(-5000,2525)","0","pure_quanta_power","I20";
;
CDS_LIB"pure_quanta_power"
HDL_POWER"GND";
"A"2;
%"Q_CAP"
"1","(-5000,2775)","0","pure_quanta","I21";
;
LOCATION"PC258"
$SEC"1"
CDS_SEC"1"
MATERIAL"X7R"
TOLERANCE"10%"
VALUE"0.022UF"
PART_NUMBER"CH3224K1B01"
VOLTAGE"25V"
PACK_TYPE"0402"
CDS_LIB"pure_quanta";
"B"
$PN"2"2;
"A"
$PN"1"19;
%"Q_RES"
"2","(-4150,2675)","0","pure_quanta","I22";
;
LOCATION"PR470"
$SEC"1"
CDS_SEC"1"
WATTAGE"1/16W"
MATERIAL"CHIP"
TOLERANCE"1%"
VALUE"10K"
PART_NUMBER"TMP_QCS31002FB26"
PACK_TYPE"0402LF"
CDS_LIB"pure_quanta";
"A"
$PN"1"25;
"B"
$PN"2"18;
%"Q_RES"
"2","(-4700,4450)","0","pure_quanta","I23";
;
LOCATION"PR465"
SEC"1"
WATTAGE"1/16W"
MATERIAL"CHIP"
TOLERANCE"5%"
VALUE"10K"
PACK_TYPE"0402LF"
PART_NUMBER"TMP_QCS31002JB28"
CDS_LIB"pure_quanta"
SEC_TYPE"0402LF";
"A"
$PN"1"3;
"B"
$PN"2"10;
%"Q_CAP"
"1","(-4475,3800)","0","pure_quanta","I24";
;
LOCATION"PC209"
SEC"1"
MATERIAL"X7R"
TOLERANCE"10%"
VALUE"0.22UF"
PART_NUMBER"CH4223K1B00"
VOLTAGE"16V"
PACK_TYPE"0402"
CDS_LIB"pure_quanta"
SEC_TYPE"0402"
ROOM"VR_CORE1_POWER_STAGE_1";
"B"
$PN"2"17;
"A"
$PN"1"24;
%"UNIVERSAL_POWER"
"1","(-4700,4725)","0","mstr_symbols","I25";
;
HDL_POWER"P3V3_STBY"
CDS_LIB"mstr_symbols";
"A"3;
%"Q_CAP"
"2","(-3575,2875)","0","pure_quanta","I26";
;
LOCATION"PC259"
$SEC"1"
CDS_SEC"1"
MATERIAL"X7R"
TOLERANCE"10%"
VALUE"220PF"
PART_NUMBER"TMP_QCH12206KB14"
VOLTAGE"50V"
PACK_TYPE"0402"
CDS_LIB"pure_quanta";
"A"
$PN"1"25;
"B"
$PN"2"16;
%"Q_RES"
"1","(-3575,3200)","0","pure_quanta","I27";
;
LOCATION"PR471"
$SEC"1"
CDS_SEC"1"
MATERIAL"CHIP"
VALUE"20K"
PART_NUMBER"CS32002FB29"
PACK_TYPE"0402LF"
CDS_LIB"pure_quanta"
WATTAGE"1/16W"
TOLERANCE"1%";
"B"
$PN"2"16;
"A"
$PN"1"25;
%"Q_INDUCTOR"
"1","(-3575,3675)","0","pure_quanta","I28";
;
LOCATION"PL78"
$SEC"1"
CDS_SEC"1"
MATERIAL"IND"
VALUE"1UH"
PACK_TYPE"SMLF"
PART_NUMBER"CV-10B0MZ13"
CDS_LIB"pure_quanta"
NEEDS_NO_SIZE"TRUE";
"1"
$PN"1"17;
"2"
$PN"2"15;
%"Q_CAP"
"1","(-2275,3400)","0","pure_quanta","I31";
;
LOCATION"PC288"
$SEC"1"
CDS_SEC"1"
MATERIAL"X6S"
TOLERANCE"20%"
VALUE"22UF"
VOLTAGE"4V"
PACK_TYPE"0805"
CDS_LIB"pure_quanta"
PART_NUMBER"TMP_QCH622KMEA01";
"B"
$PN"2"14;
"A"
$PN"1"15;
%"Q_CAP"
"1","(-2025,3400)","0","pure_quanta","I32";
;
LOCATION"PC260"
$SEC"1"
CDS_SEC"1"
MATERIAL"EMPTY"
TOLERANCE"20%"
VALUE"22UF"
VOLTAGE"4V"
PACK_TYPE"0805"
CDS_LIB"pure_quanta"
PART_NUMBER"TMP_QCH622KMEA01";
"B"
$PN"2"14;
"A"
$PN"1"15;
%"Q_CAP"
"1","(-1700,3400)","0","pure_quanta","I33";
;
LOCATION"PC261"
$SEC"1"
CDS_SEC"1"
MATERIAL"EMPTY"
TOLERANCE"20%"
VALUE"22UF"
VOLTAGE"4V"
PACK_TYPE"0805"
CDS_LIB"pure_quanta"
PART_NUMBER"TMP_QCH622KMEA01";
"B"
$PN"2"14;
"A"
$PN"1"15;
%"UNIVERSAL_GND"
"1","(-500,2850)","0","pure_quanta_power","I34";
;
CDS_LIB"pure_quanta_power"
HDL_POWER"GND";
"A"4;
%"P1V0"
"1","(-500,4025)","0","pure_quanta_power","I36";
;
HDL_POWER"PVDD18_S5_P0"
CDS_LIB"pure_quanta_power";
"A"15;
%"Q_RES"
"1","(-2600,2400)","0","pure_quanta","I38";
;
LOCATION"PR434"
$SEC"1"
CDS_SEC"1"
WATTAGE"1/16W"
MATERIAL"CHIP"
TOLERANCE"1%"
VALUE"10"
PART_NUMBER"CS01002FB07"
PACK_TYPE"0402LF"
CDS_LIB"pure_quanta";
"B"
$PN"2"12;
"A"
$PN"1"16;
%"Q_RES"
"2","(-2600,2100)","1","pure_quanta","I39";
;
LOCATION"PR435"
$SEC"1"
CDS_SEC"1"
WATTAGE"1/16W"
MATERIAL"CHIP"
TOLERANCE"5%"
VALUE"0"
PART_NUMBER"CS00002JB38"
PACK_TYPE"0402LF"
CDS_LIB"pure_quanta";
"A"
$PN"1"18;
"B"
$PN"2"13;
%"Q_RES"
"1","(-3575,1850)","1","pure_quanta","I42";
;
LOCATION"PR418"
$SEC"1"
CDS_SEC"1"
WATTAGE"1/16W"
MATERIAL"CHIP"
TOLERANCE"1%"
VALUE"49.9"
PART_NUMBER"CS04992FB07"
PACK_TYPE"0402LF"
CDS_LIB"pure_quanta";
"B"
$PN"2"18;
"A"
$PN"1"5;
%"UNIVERSAL_GND"
"1","(-3575,1600)","0","pure_quanta_power","I43";
;
CDS_LIB"pure_quanta_power"
HDL_POWER"GND";
"A"5;
%"Q_CAP"
"1","(-4575,2950)","1","pure_quanta","I44";
;
LOCATION"PC113"
$SEC"1"
CDS_SEC"1"
MATERIAL"X7R"
TOLERANCE"10%"
VALUE"0.1UF"
PART_NUMBER"CH4104K1B00"
VOLTAGE"25V"
PACK_TYPE"0402"
CDS_LIB"pure_quanta";
"B"
$PN"2"18;
"A"
$PN"1"19;
%"Q_CAP"
"1","(-8350,4200)","0","pure_quanta","I45";
;
LOCATION"PC111"
$SEC"1"
CDS_SEC"1"
MATERIAL"X6S"
TOLERANCE"10%"
VALUE"10UF"
PART_NUMBER"CH6104KEA00"
VOLTAGE"25V"
PACK_TYPE"C0805"
CDS_LIB"pure_quanta";
"B"
$PN"2"27;
"A"
$PN"1"26;
%"UNIVERSAL_GND"
"1","(-7950,3825)","0","pure_quanta_power","I46";
;
CDS_LIB"pure_quanta_power"
HDL_POWER"GND";
"A"27;
%"Q_CAP"
"1","(-2925,3400)","0","pure_quanta","I48";
;
LOCATION"PC114"
$SEC"1"
CDS_SEC"1"
MATERIAL"X6S"
TOLERANCE"20%"
VALUE"22UF"
PART_NUMBER"TMP_QCH622KMEA01"
VOLTAGE"4V"
PACK_TYPE"0805"
CDS_LIB"pure_quanta";
"B"
$PN"2"14;
"A"
$PN"1"15;
%"Q_CAP"
"1","(-7975,4200)","0","pure_quanta","I5";
;
LOCATION"PC227"
$SEC"1"
CDS_SEC"1"
MATERIAL"X6S"
TOLERANCE"10%"
VALUE"10UF"
PART_NUMBER"CH6104KEA00"
VOLTAGE"25V"
PACK_TYPE"C0805"
CDS_LIB"pure_quanta";
"B"
$PN"2"27;
"A"
$PN"1"26;
%"UNIVERSAL_GND"
"1","(-8050,3000)","0","pure_quanta_power","I50";
;
CDS_LIB"pure_quanta_power"
HDL_POWER"GND";
"A"6;
%"Q_RES"
"1","(-7075,3450)","0","pure_quanta","I51";
;
LOCATION"PR417"
$SEC"1"
CDS_SEC"1"
PACK_TYPE"0402LF"
WATTAGE"1/16W"
MATERIAL"CHIP"
TOLERANCE"5%"
VALUE"0"
PART_NUMBER"CS00002JB38"
CDS_LIB"pure_quanta";
"B"
$PN"2"28;
"A"
$PN"1"6;
%"Q_CAPP"
"1","(-1425,3400)","0","pure_quanta","I54";
;
LOCATION"PC115"
$SEC"1"
CDS_SEC"1"
MATERIAL"OSCON"
TOLERANCE"20%"
VALUE"390UF"
PART_NUMBER"CC7390JMZ12"
VOLTAGE"2.5V"
PACK_TYPE"SMLF"
CDS_LIB"pure_quanta";
"A"
$PN"1"15;
"B"
$PN"2"14;
%"Q_RES"
"2","(-500,3375)","0","pure_quanta","I56";
;
LOCATION"PR439"
$SEC"1"
CDS_SEC"1"
WATTAGE"1/16W"
MATERIAL"CHIP"
TOLERANCE"1%"
VALUE"1K"
PART_NUMBER"TMP_QCS21002FB24"
PACK_TYPE"0402LF"
CDS_LIB"pure_quanta";
"A"
$PN"1"15;
"B"
$PN"2"4;
%"Q_CAP"
"1","(-1100,3400)","0","pure_quanta","I57";
;
LOCATION"PC215"
SEC"1"
MATERIAL"X7R"
TOLERANCE"10%"
VALUE"0.1UF"
PART_NUMBER"CH4104K1B00"
VOLTAGE"25V"
PACK_TYPE"0402"
CDS_LIB"pure_quanta"
SEC_TYPE"0402";
"B"
$PN"2"14;
"A"
$PN"1"15;
%"UNIVERSAL_GND"
"1","(-1100,3025)","0","pure_quanta_power","I58";
;
CDS_LIB"pure_quanta_power"
HDL_POWER"GND";
"A"14;
%"Q_RES"
"1","(-1700,2900)","0","pure_quanta","I59";
;
LOCATION"PR438"
$SEC"1"
CDS_SEC"1"
WATTAGE"1/16W"
MATERIAL"CHIP"
TOLERANCE"1%"
VALUE"49.9"
PART_NUMBER"CS04992FB07"
PACK_TYPE"0402LF"
CDS_LIB"pure_quanta";
"B"
$PN"2"15;
"A"
$PN"1"16;
%"P1V0_AUX"
"1","(-9146,4645)","0","mstr_symbols","I6";
;
HDL_POWER"P12V_STBY"
CDS_LIB"mstr_symbols"
BODY_TYPE"PLUMBING"
VOLTAGE"1.0V"
ROOM"VR_DDR1_POWER_STAGE";
"A"23;
%"Q_CAP"
"1","(-2475,3400)","0","pure_quanta","I60";
;
LOCATION"PC285"
$SEC"1"
CDS_SEC"1"
MATERIAL"X6S"
TOLERANCE"20%"
VALUE"22UF"
VOLTAGE"4V"
PACK_TYPE"0805"
CDS_LIB"pure_quanta"
PART_NUMBER"TMP_QCH622KMEA01";
"B"
$PN"2"14;
"A"
$PN"1"15;
%"Q_RES"
"1","(-3650,4150)","0","pure_quanta","I62";
;
LOCATION"R177"
$SEC"1"
CDS_SEC"1"
VALUE"33"
CDS_LIB"pure_quanta"
BOM_COST"MEM"
WATTAGE"1/16W"
MATERIAL"CHIP"
TOLERANCE"5%"
PART_NUMBER"CS03302JB29"
PACK_TYPE"0402LF"
ROOM"RST_CPU0_PLD_TO_DIMM";
"B"
$PN"2"11;
"A"
$PN"1"10;
%"UNIVERSAL_GND"
"1","(-8575,3250)","0","pure_quanta_power","I63";
;
CDS_LIB"pure_quanta_power"
HDL_POWER"GND";
"A"7;
%"Q_CAP"
"1","(-8575,3450)","2","pure_quanta","I64";
;
LOCATION"C674"
$SEC"1"
CDS_SEC"1"
MATERIAL"EMPTY"
TOLERANCE"10%"
VALUE"0.1UF"
PART_NUMBER"CH4104K1B00"
VOLTAGE"25V"
PACK_TYPE"0402"
CDS_LIB"pure_quanta"
ROOM"VR_DDR0_CTRL";
"B"
$PN"2"7;
"A"
$PN"1"22;
%"UNIVERSAL_GND"
"1","(-7575,2400)","0","pure_quanta_power","I7";
;
CDS_LIB"pure_quanta_power"
HDL_POWER"GND";
"A"8;
%"UNIVERSAL_GND"
"1","(-6700,2375)","0","pure_quanta_power","I8";
;
CDS_LIB"pure_quanta_power"
HDL_POWER"GND";
"A"9;
%"Q_CAP"
"1","(-7575,2625)","2","pure_quanta","I9";
;
LOCATION"PC212"
SEC"1"
MATERIAL"X6S"
TOLERANCE"10%"
VALUE"1UF"
PART_NUMBER"CH5104KEB02"
VOLTAGE"25V"
PACK_TYPE"C0402"
CDS_LIB"pure_quanta"
SIGNAL_MODEL"DEFAULT_CAPACITOR_100000PF_2_1"
SEC_TYPE"C0402"
ROOM"VR_DDR0_CTRL";
"B"
$PN"2"8;
"A"
$PN"1"29;
END.
